FILE_TYPE=LIBRARY_PARTS;
primitive 'TPS3895ADRYR';
  pin
    'ENABLE':
      PIN_NUMBER='(1)';
      INPUT_LOAD='(-0.01,0.01)';
    'GND':
      PIN_NUMBER='(2)';
      PINUSE='POWER';
      NO_LOAD_CHECK='Both';
      NO_IO_CHECK='Both';
      NO_ASSERT_CHECK='TRUE';
      NO_DIR_CHECK='TRUE';
      ALLOW_CONNECT='TRUE';
    'SENSE':
      PIN_NUMBER='(3)';
      BIDIRECTIONAL='TRUE';
      INPUT_LOAD='(-0.01,0.01)';
      OUTPUT_LOAD='(1.0,-1.0)';
    'SENSE_OUT':
      PIN_NUMBER='(4)';
      OUTPUT_TYPE='(OC,AND)';
      OUTPUT_LOAD='(1.0,*)';
    'CT':
      PIN_NUMBER='(5)';
      BIDIRECTIONAL='TRUE';
      INPUT_LOAD='(-0.01,0.01)';
      OUTPUT_LOAD='(1.0,-1.0)';
    'VCC':
      PIN_NUMBER='(6)';
      PINUSE='POWER';
      NO_LOAD_CHECK='Both';
      NO_IO_CHECK='Both';
      NO_ASSERT_CHECK='TRUE';
      NO_DIR_CHECK='TRUE';
      ALLOW_CONNECT='TRUE';
  end_pin;
  body
    PART_NAME='TPS3895ADRYR';
    BODY_NAME='TPS3895ADRYR';
    PHYS_DES_PREFIX='U';
    CLASS='IC';
  end_body;
end_primitive;

END.
